# BASEBOARD_FAB2 (Tioga Pass) — schematic netlist excerpt (pin names and nets, part order shuffled) for the footprints in the layout excerpt that follows; sources: Cadence DE-HDL packaged netlist, KiCad conversion of Wiwynn_Tioga_Pass_MB.brd

R3F1  RES  0.0 5% EMPTY  pkg 0402  page 104 : A = CLK_322M_156M_CPU1_OSC_VRM_DN ; B = CLK_156M_OSC_CPU1_HFI_DN
C1B12  CAP  220PF 50V 10% X7R  pkg 0402LF  page 226 : A = VR_PVDDQ_KLM_AVSP ; B = VSENSE_PVDDQ_KLM_N

(kicad_pcb
	(version 20260206)
	(generator "pcbnew")
	(generator_version "10.0")
	(general
		(thickness 1.6)
		(legacy_teardrops no)
	)
	(paper "A4")
	(title_block
		(title "Wiwynn_Tioga_Pass_MB.brd")
		(comment 1 "Tioga Pass / footprints 182-183 of 4770")
	)
	(layers
		(0 "F.Cu" signal "TOP")
		(4 "In1.Cu" signal "L2GND")
		(6 "In2.Cu" signal "L3")
		(8 "In3.Cu" signal "L4GND")
		(10 "In4.Cu" signal "L5")
		(12 "In5.Cu" signal "L6GND")
		(14 "In6.Cu" signal "L7VCC")
		(16 "In7.Cu" signal "L8VCC")
		(18 "In8.Cu" signal "L9GND")
		(20 "In9.Cu" signal "L10")
		(22 "In10.Cu" signal "L11GND")
		(24 "In11.Cu" signal "L12")
		(26 "In12.Cu" signal "L13GND")
		(2 "B.Cu" signal "BOTTOM")
		(9 "F.Adhes" user "F.Adhesive")
		(11 "B.Adhes" user "B.Adhesive")
		(13 "F.Paste" user "Package Geometry/Pastemask Top")
		(15 "B.Paste" user "Package Geometry/Pastemask Bottom")
		(5 "F.SilkS" user "Ref Des/Silkscreen Top")
		(7 "B.SilkS" user "Ref Des/Silkscreen Bottom")
		(1 "F.Mask" user "Board Geometry/Soldermask Top")
		(3 "B.Mask" user "Board Geometry/Soldermask Bottom")
		(17 "Dwgs.User" user "User.Drawings")
		(19 "Cmts.User" user "User.Comments")
		(21 "Eco1.User" user "User.Eco1")
		(23 "Eco2.User" user "User.Eco2")
		(25 "Edge.Cuts" user "Board Geometry/Outline")
		(27 "Margin" user)
		(31 "F.CrtYd" user "Package Geometry/Place Bound Top")
		(29 "B.CrtYd" user "Package Geometry/Place Bound Bottom")
		(35 "F.Fab" user "Ref Des/Assembly Top")
		(33 "B.Fab" user "Ref Des/Assembly Bottom")
	)
	(footprint ""
		(layer "F.Cu")
		(at -2.5146 -125.222)
		(property "Reference" "C1B12"
			(at 0 0 0)
			(layer "F.SilkS")
			(hide yes)
			(effects
				(font
					(size 1.27 1.27)
				)
			)
		)
		(property "Value" ""
			(at 0 0 0)
			(layer "F.Fab")
			(effects
				(font
					(size 1.27 1.27)
				)
			)
		)
		(duplicate_pad_numbers_are_jumpers no)
		(fp_rect
			(start -0.3048 0.9906)
			(end 0.3048 -0.1016)
			(stroke
				(width 0)
				(type default)
			)
			(fill no)
			(layer "F.CrtYd")
		)
		(fp_line
			(start -0.3048 -0.1016)
			(end -0.3048 0.9906)
			(stroke
				(width 0.1)
				(type default)
			)
			(layer "F.Fab")
		)
		(fp_line
			(start -0.3048 0.9906)
			(end 0.3048 0.9906)
			(stroke
				(width 0.1)
				(type default)
			)
			(layer "F.Fab")
		)
		(fp_line
			(start 0.3048 -0.1016)
			(end -0.3048 -0.1016)
			(stroke
				(width 0.1)
				(type default)
			)
			(layer "F.Fab")
		)
		(fp_line
			(start 0.3048 0.9906)
			(end 0.3048 -0.1016)
			(stroke
				(width 0.1)
				(type default)
			)
			(layer "F.Fab")
		)
		(pad "1" smd rect
			(at 0 0)
			(size 0.508 0.508)
			(layers "F.Cu" "F.Mask" "F.Paste")
			(net "VR_PVDDQ_KLM_AVSP")
		)
		(pad "2" smd rect
			(at 0 0.889)
			(size 0.508 0.508)
			(layers "F.Cu" "F.Mask" "F.Paste")
			(net "VSENSE_PVDDQ_KLM_N")
		)
		(zone
			(layer "F.Cu")
			(hatch none 0.5)
			(connect_pads
				(clearance 0)
			)
			(min_thickness 0.25)
			(keepout
				(tracks allowed)
				(vias not_allowed)
				(pads allowed)
				(copperpour not_allowed)
				(footprints allowed)
			)
			(placement
				(enabled no)
				(sheetname "")
			)
			(fill
				(thermal_gap 0.5)
				(thermal_bridge_width 0.5)
				(island_removal_mode 0)
			)
			(polygon
				(pts
					(xy -2.7686 -124.587) (xy -2.2606 -124.587) (xy -2.2606 -124.968) (xy -2.7686 -124.968)
				)
			)
		)
	)
	(footprint ""
		(layer "F.Cu")
		(at 155.194 -30.5308)
		(property "Reference" "R3F1"
			(at 0 0 0)
			(layer "F.SilkS")
			(hide yes)
			(effects
				(font
					(size 1.27 1.27)
				)
			)
		)
		(property "Value" ""
			(at 0 0 0)
			(layer "F.Fab")
			(effects
				(font
					(size 1.27 1.27)
				)
			)
		)
		(duplicate_pad_numbers_are_jumpers no)
		(fp_poly
			(pts
				(xy -0.2794 -0.1016) (xy 0.2794 -0.1016) (xy 0.2794 0.9906) (xy -0.2794 0.9906)
			)
			(stroke
				(width 0)
				(type default)
			)
			(fill no)
			(layer "F.CrtYd")
		)
		(fp_line
			(start -0.2794 -0.1016)
			(end -0.2794 0.9906)
			(stroke
				(width 0.1)
				(type default)
			)
			(layer "F.Fab")
		)
		(fp_line
			(start -0.2794 0.9906)
			(end 0.2794 0.9906)
			(stroke
				(width 0.1)
				(type default)
			)
			(layer "F.Fab")
		)
		(fp_line
			(start 0.2794 -0.1016)
			(end -0.2794 -0.1016)
			(stroke
				(width 0.1)
				(type default)
			)
			(layer "F.Fab")
		)
		(fp_line
			(start 0.2794 0.9906)
			(end 0.2794 -0.1016)
			(stroke
				(width 0.1)
				(type default)
			)
			(layer "F.Fab")
		)
		(pad "1" smd rect
			(at 0 0)
			(size 0.508 0.508)
			(layers "F.Cu" "F.Mask" "F.Paste")
			(net "CLK_322M_156M_CPU1_OSC_VRM_DN")
		)
		(pad "2" smd rect
			(at 0 0.889)
			(size 0.508 0.508)
			(layers "F.Cu" "F.Mask" "F.Paste")
			(net "CLK_156M_OSC_CPU1_HFI_DN")
		)
		(zone
			(layer "F.Cu")
			(hatch none 0.5)
			(connect_pads
				(clearance 0)
			)
			(min_thickness 0.25)
			(keepout
				(tracks allowed)
				(vias not_allowed)
				(pads allowed)
				(copperpour not_allowed)
				(footprints allowed)
			)
			(placement
				(enabled no)
				(sheetname "")
			)
			(fill
				(thermal_gap 0.5)
				(thermal_bridge_width 0.5)
				(island_removal_mode 0)
			)
			(polygon
				(pts
					(xy 154.94 -30.2768) (xy 155.448 -30.2768) (xy 155.448 -29.8958) (xy 154.94 -29.8958)
				)
			)
		)
		(zone
			(layer "F.Cu")
			(hatch none 0.5)
			(connect_pads
				(clearance 0)
			)
			(min_thickness 0.25)
			(keepout
				(tracks not_allowed)
				(vias allowed)
				(pads allowed)
				(copperpour not_allowed)
				(footprints allowed)
			)
			(placement
				(enabled no)
				(sheetname "")
			)
			(fill
				(thermal_gap 0.5)
				(thermal_bridge_width 0.5)
				(island_removal_mode 0)
			)
			(polygon
				(pts
					(xy 154.94 -29.8958) (xy 155.448 -29.8958) (xy 155.448 -30.2768) (xy 154.94 -30.2768)
				)
			)
		)
	)
)
